# T6G (Grand Teton) — schematic netlist excerpt (pin names and nets, part order shuffled) for the footprints in the layout excerpt that follows; sources: Cadence DE-HDL packaged netlist, KiCad conversion of 04192023_DAF0TMB3IC0_F0TG_MB_C_brd_V02_OCP.brd

PR362  Q_RES  0 5% CHIP  pkg 0402LF  page 198 : A = PVDDCR_SOC_P0_VOS1 ; B = PVDDCR_SOC_P0
C3914  Q_CAP  22UF 4V 20% X6S  pkg C0402  page 74 : A = PVDDCR_SOC_P1 ; B = GND

(kicad_pcb
	(version 20260206)
	(generator "pcbnew")
	(generator_version "10.0")
	(general
		(thickness 1.6)
		(legacy_teardrops no)
	)
	(paper "A4")
	(title_block
		(title "04192023_DAF0TMB3IC0_F0TG_MB_C_brd_V02_OCP.brd")
		(comment 1 "Grand Teton / footprints 5655-5656 of 8354")
	)
	(layers
		(0 "F.Cu" signal "TOP")
		(4 "In1.Cu" signal "GND")
		(6 "In2.Cu" signal "IN1")
		(8 "In3.Cu" signal "GND1")
		(10 "In4.Cu" signal "IN2")
		(12 "In5.Cu" signal "GND2")
		(14 "In6.Cu" signal "IN3")
		(16 "In7.Cu" signal "GND3")
		(18 "In8.Cu" signal "VCC")
		(20 "In9.Cu" signal "VCC1")
		(22 "In10.Cu" signal "GND4")
		(24 "In11.Cu" signal "IN4")
		(26 "In12.Cu" signal "GND5")
		(28 "In13.Cu" signal "IN5")
		(30 "In14.Cu" signal "GND6")
		(32 "In15.Cu" signal "IN6")
		(34 "In16.Cu" signal "GND7")
		(2 "B.Cu" signal "BOTTOM")
		(9 "F.Adhes" user "F.Adhesive")
		(11 "B.Adhes" user "B.Adhesive")
		(13 "F.Paste" user "Package Geometry/Pastemask Top")
		(15 "B.Paste" user "Package Geometry/Pastemask Bottom")
		(5 "F.SilkS" user "Ref Des/Silkscreen Top")
		(7 "B.SilkS" user "Ref Des/Silkscreen Bottom")
		(1 "F.Mask" user "Board Geometry/Soldermask Top")
		(3 "B.Mask" user "Board Geometry/Soldermask Bottom")
		(17 "Dwgs.User" user "User.Drawings")
		(19 "Cmts.User" user "User.Comments")
		(21 "Eco1.User" user "User.Eco1")
		(23 "Eco2.User" user "User.Eco2")
		(25 "Edge.Cuts" user "Board Geometry/Outline")
		(27 "Margin" user)
		(31 "F.CrtYd" user "Package Geometry/Place Bound Top")
		(29 "B.CrtYd" user "Package Geometry/Place Bound Bottom")
		(35 "F.Fab" user "Ref Des/Assembly Top")
		(33 "B.Fab" user "Ref Des/Assembly Bottom")
	)
	(footprint ""
		(layer "B.Cu")
		(at 121.685812 -257.930396)
		(property "Reference" "C3914"
			(at 0 0 0)
			(layer "B.SilkS")
			(hide yes)
			(effects
				(font
					(size 1.27 1.27)
				)
				(justify mirror)
			)
		)
		(property "Value" ""
			(at 0 0 0)
			(layer "B.Fab")
			(effects
				(font
					(size 1.27 1.27)
				)
				(justify mirror)
			)
		)
		(duplicate_pad_numbers_are_jumpers no)
		(fp_line
			(start -0.7874 -0.4064)
			(end -0.7874 0.4064)
			(stroke
				(width 0.1524)
				(type default)
			)
			(layer "B.SilkS")
		)
		(fp_line
			(start -0.7874 0.4064)
			(end 0.7874 0.4064)
			(stroke
				(width 0.1524)
				(type default)
			)
			(layer "B.SilkS")
		)
		(fp_line
			(start 0.7874 -0.4064)
			(end -0.7874 -0.4064)
			(stroke
				(width 0.1524)
				(type default)
			)
			(layer "B.SilkS")
		)
		(fp_line
			(start 0.7874 0.4064)
			(end 0.7874 -0.4064)
			(stroke
				(width 0.1524)
				(type default)
			)
			(layer "B.SilkS")
		)
		(fp_line
			(start -0.67945 -0.3048)
			(end -0.67945 0.3048)
			(stroke
				(width 0.1)
				(type default)
			)
			(layer "B.Fab")
		)
		(fp_line
			(start -0.67945 0.3048)
			(end -0.120396 0.3048)
			(stroke
				(width 0.1)
				(type default)
			)
			(layer "B.Fab")
		)
		(fp_line
			(start -0.12065 -0.3048)
			(end -0.67945 -0.3048)
			(stroke
				(width 0.1)
				(type default)
			)
			(layer "B.Fab")
		)
		(fp_line
			(start -0.12065 -0.2794)
			(end -0.12065 -0.3048)
			(stroke
				(width 0.1)
				(type default)
			)
			(layer "B.Fab")
		)
		(fp_line
			(start -0.120396 0.2794)
			(end 0.12065 0.2794)
			(stroke
				(width 0.1)
				(type default)
			)
			(layer "B.Fab")
		)
		(fp_line
			(start -0.120396 0.3048)
			(end -0.120396 0.2794)
			(stroke
				(width 0.1)
				(type default)
			)
			(layer "B.Fab")
		)
		(fp_line
			(start 0.12065 -0.305054)
			(end 0.12065 -0.2794)
			(stroke
				(width 0.1)
				(type default)
			)
			(layer "B.Fab")
		)
		(fp_line
			(start 0.12065 -0.2794)
			(end -0.12065 -0.2794)
			(stroke
				(width 0.1)
				(type default)
			)
			(layer "B.Fab")
		)
		(fp_line
			(start 0.12065 0.2794)
			(end 0.12065 0.3048)
			(stroke
				(width 0.1)
				(type default)
			)
			(layer "B.Fab")
		)
		(fp_line
			(start 0.12065 0.3048)
			(end 0.67945 0.3048)
			(stroke
				(width 0.1)
				(type default)
			)
			(layer "B.Fab")
		)
		(fp_line
			(start 0.67945 -0.305054)
			(end 0.12065 -0.305054)
			(stroke
				(width 0.1)
				(type default)
			)
			(layer "B.Fab")
		)
		(fp_line
			(start 0.67945 0.3048)
			(end 0.67945 -0.305054)
			(stroke
				(width 0.1)
				(type default)
			)
			(layer "B.Fab")
		)
		(pad "1" smd circle
			(at 0.40005 0 180)
			(size 0 0)
			(layers "B.Cu" "B.Mask" "B.Paste")
			(net "PVDDCR_SOC_P1")
		)
		(pad "2" smd circle
			(at -0.40005 0 180)
			(size 0 0)
			(layers "B.Cu" "B.Mask" "B.Paste")
			(net "GND")
		)
	)
	(footprint ""
		(layer "B.Cu")
		(at 401.485608 -174.505874 90)
		(property "Reference" "PR362"
			(at 0 0 90)
			(layer "B.SilkS")
			(hide yes)
			(effects
				(font
					(size 1.27 1.27)
				)
				(justify mirror)
			)
		)
		(property "Value" ""
			(at 0 0 90)
			(layer "B.Fab")
			(effects
				(font
					(size 1.27 1.27)
				)
				(justify mirror)
			)
		)
		(duplicate_pad_numbers_are_jumpers no)
		(fp_line
			(start 0.7874 -0.4064)
			(end -0.7874 -0.4064)
			(stroke
				(width 0.1524)
				(type default)
			)
			(layer "B.SilkS")
		)
		(fp_line
			(start -0.7874 -0.4064)
			(end -0.7874 0.4064)
			(stroke
				(width 0.1524)
				(type default)
			)
			(layer "B.SilkS")
		)
		(fp_line
			(start 0.7874 0.4064)
			(end 0.7874 -0.4064)
			(stroke
				(width 0.1524)
				(type default)
			)
			(layer "B.SilkS")
		)
		(fp_line
			(start -0.7874 0.4064)
			(end 0.7874 0.4064)
			(stroke
				(width 0.1524)
				(type default)
			)
			(layer "B.SilkS")
		)
		(fp_line
			(start 0.67945 -0.305054)
			(end 0.12065 -0.305054)
			(stroke
				(width 0.1)
				(type default)
			)
			(layer "B.Fab")
		)
		(fp_line
			(start 0.12065 -0.305054)
			(end 0.12065 -0.2794)
			(stroke
				(width 0.1)
				(type default)
			)
			(layer "B.Fab")
		)
		(fp_line
			(start -0.12065 -0.3048)
			(end -0.67945 -0.3048)
			(stroke
				(width 0.1)
				(type default)
			)
			(layer "B.Fab")
		)
		(fp_line
			(start -0.67945 -0.3048)
			(end -0.67945 0.3048)
			(stroke
				(width 0.1)
				(type default)
			)
			(layer "B.Fab")
		)
		(fp_line
			(start 0.12065 -0.2794)
			(end -0.12065 -0.2794)
			(stroke
				(width 0.1)
				(type default)
			)
			(layer "B.Fab")
		)
		(fp_line
			(start -0.12065 -0.2794)
			(end -0.12065 -0.3048)
			(stroke
				(width 0.1)
				(type default)
			)
			(layer "B.Fab")
		)
		(fp_line
			(start 0.12065 0.2794)
			(end 0.12065 0.3048)
			(stroke
				(width 0.1)
				(type default)
			)
			(layer "B.Fab")
		)
		(fp_line
			(start -0.120396 0.2794)
			(end 0.12065 0.2794)
			(stroke
				(width 0.1)
				(type default)
			)
			(layer "B.Fab")
		)
		(fp_line
			(start 0.67945 0.3048)
			(end 0.67945 -0.305054)
			(stroke
				(width 0.1)
				(type default)
			)
			(layer "B.Fab")
		)
		(fp_line
			(start 0.12065 0.3048)
			(end 0.67945 0.3048)
			(stroke
				(width 0.1)
				(type default)
			)
			(layer "B.Fab")
		)
		(fp_line
			(start -0.120396 0.3048)
			(end -0.120396 0.2794)
			(stroke
				(width 0.1)
				(type default)
			)
			(layer "B.Fab")
		)
		(fp_line
			(start -0.67945 0.3048)
			(end -0.120396 0.3048)
			(stroke
				(width 0.1)
				(type default)
			)
			(layer "B.Fab")
		)
		(pad "1" smd circle
			(at 0.40005 0 270)
			(size 0 0)
			(layers "B.Cu" "B.Mask" "B.Paste")
			(net "PVDDCR_SOC_P0_VOS1")
		)
		(pad "2" smd circle
			(at -0.40005 0 270)
			(size 0 0)
			(layers "B.Cu" "B.Mask" "B.Paste")
			(net "PVDDCR_SOC_P0")
		)
	)
)
